# SCM (Grand Teton) — schematic netlist excerpt (pin names and nets, part order shuffled) for the footprints in the layout excerpt that follows; sources: Cadence DE-HDL packaged netlist, KiCad conversion of 12092022_DA0F0TMDCD0_F0T_Management_Board_D_brd_V3_OCP.brd

Q13  MOSFET_NCH_DUAL  PJT138K IC  pkg SOT363XD  page 50
  S1  = GND
  G1  = PWRGD_P1V0_AUX_DELAY
  D1  = LED_D22_R1

R657  Q_RES  10K 1% EMPTY  pkg 0402LF  page 21 : A = P3V3_AUX ; B = EMMC_DT2_R

(kicad_pcb
	(version 20260206)
	(generator "pcbnew")
	(generator_version "10.0")
	(general
		(thickness 1.6)
		(legacy_teardrops no)
	)
	(paper "A4")
	(title_block
		(title "12092022_DA0F0TMDCD0_F0T_Management_Board_D_brd_V3_OCP.brd")
		(comment 1 "Grand Teton / footprints 114-115 of 1440")
	)
	(layers
		(0 "F.Cu" signal "TOP")
		(4 "In1.Cu" signal "GND")
		(6 "In2.Cu" signal "IN1")
		(8 "In3.Cu" signal "GND1")
		(10 "In4.Cu" signal "IN2")
		(12 "In5.Cu" signal "VCC")
		(14 "In6.Cu" signal "VCC1")
		(16 "In7.Cu" signal "IN3")
		(18 "In8.Cu" signal "GND2")
		(20 "In9.Cu" signal "IN4")
		(22 "In10.Cu" signal "GND3")
		(2 "B.Cu" signal "BOTTOM")
		(9 "F.Adhes" user "F.Adhesive")
		(11 "B.Adhes" user "B.Adhesive")
		(13 "F.Paste" user "Package Geometry/Pastemask Top")
		(15 "B.Paste" user "Package Geometry/Pastemask Bottom")
		(5 "F.SilkS" user "Ref Des/Silkscreen Top")
		(7 "B.SilkS" user "Ref Des/Silkscreen Bottom")
		(1 "F.Mask" user "Board Geometry/Soldermask Top")
		(3 "B.Mask" user "Board Geometry/Soldermask Bottom")
		(17 "Dwgs.User" user "User.Drawings")
		(19 "Cmts.User" user "User.Comments")
		(21 "Eco1.User" user "User.Eco1")
		(23 "Eco2.User" user "User.Eco2")
		(25 "Edge.Cuts" user "Board Geometry/Outline")
		(27 "Margin" user)
		(31 "F.CrtYd" user "Package Geometry/Place Bound Top")
		(29 "B.CrtYd" user "Package Geometry/Place Bound Bottom")
		(35 "F.Fab" user "Ref Des/Assembly Top")
		(33 "B.Fab" user "Ref Des/Assembly Bottom")
	)
	(footprint ""
		(layer "F.Cu")
		(at 63.373 -11.176)
		(property "Reference" "Q13"
			(at -1.4224 -1.768348 0)
			(unlocked yes)
			(layer "F.SilkS")
			(effects
				(font
					(size 0.7874 0.5842)
					(thickness 0.1524)
				)
				(justify left)
			)
		)
		(property "Value" ""
			(at 0 0 0)
			(layer "F.Fab")
			(effects
				(font
					(size 1.27 1.27)
				)
			)
		)
		(duplicate_pad_numbers_are_jumpers no)
		(fp_line
			(start -1.332738 -1.100074)
			(end -0.4826 -1.100074)
			(stroke
				(width 0.1524)
				(type default)
			)
			(layer "F.SilkS")
		)
		(fp_line
			(start -1.332738 1.100074)
			(end -1.332738 -1.100074)
			(stroke
				(width 0.1524)
				(type default)
			)
			(layer "F.SilkS")
		)
		(fp_line
			(start -0.4826 -1.100074)
			(end 0 -0.541274)
			(stroke
				(width 0.1524)
				(type default)
			)
			(layer "F.SilkS")
		)
		(fp_line
			(start 0 -0.541274)
			(end 0.4826 -1.100074)
			(stroke
				(width 0.1524)
				(type default)
			)
			(layer "F.SilkS")
		)
		(fp_line
			(start 0.4826 -1.100074)
			(end 1.332738 -1.100074)
			(stroke
				(width 0.1524)
				(type default)
			)
			(layer "F.SilkS")
		)
		(fp_line
			(start 1.332738 -1.100074)
			(end 1.332738 1.100074)
			(stroke
				(width 0.1524)
				(type default)
			)
			(layer "F.SilkS")
		)
		(fp_line
			(start 1.332738 1.100074)
			(end -1.332738 1.100074)
			(stroke
				(width 0.1524)
				(type default)
			)
			(layer "F.SilkS")
		)
		(fp_poly
			(pts
				(xy -2.2352 -0.298958) (xy -2.2352 -1.001014) (xy -1.533144 -0.649986)
			)
			(stroke
				(width 0)
				(type default)
			)
			(fill yes)
			(layer "F.SilkS")
		)
		(fp_line
			(start -0.674878 -1.100074)
			(end 0.674878 -1.100074)
			(stroke
				(width 0.1)
				(type default)
			)
			(layer "F.Fab")
		)
		(fp_line
			(start -0.674878 1.100074)
			(end -0.674878 -1.100074)
			(stroke
				(width 0.1)
				(type default)
			)
			(layer "F.Fab")
		)
		(fp_line
			(start 0.674878 -1.100074)
			(end 0.674878 1.100074)
			(stroke
				(width 0.1)
				(type default)
			)
			(layer "F.Fab")
		)
		(fp_line
			(start 0.674878 1.100074)
			(end -0.674878 1.100074)
			(stroke
				(width 0.1)
				(type default)
			)
			(layer "F.Fab")
		)
		(fp_poly
			(pts
				(xy -2.2352 -0.298958) (xy -2.2352 -1.001014) (xy -1.533144 -0.649986)
			)
			(stroke
				(width 0)
				(type default)
			)
			(fill yes)
			(layer "F.Fab")
		)
		(pad "1" smd rect
			(at -0.94996 -0.649986 90)
			(size 0.4318 0.508)
			(layers "F.Cu" "F.Mask" "F.Paste")
			(net "GND")
		)
		(pad "2" smd rect
			(at -0.94996 0 90)
			(size 0.4318 0.508)
			(layers "F.Cu" "F.Mask" "F.Paste")
			(net "PWRGD_P1V0_AUX_DELAY")
		)
		(pad "3" smd rect
			(at -0.94996 0.649986 90)
			(size 0.4318 0.508)
			(layers "F.Cu" "F.Mask" "F.Paste")
			(net "Net_30")
		)
		(pad "4" smd rect
			(at 0.94996 0.649986 90)
			(size 0.4318 0.508)
			(layers "F.Cu" "F.Mask" "F.Paste")
			(net "Net_32")
		)
		(pad "5" smd rect
			(at 0.94996 0 90)
			(size 0.4318 0.508)
			(layers "F.Cu" "F.Mask" "F.Paste")
			(net "Net_31")
		)
		(pad "6" smd rect
			(at 0.94996 -0.649986 90)
			(size 0.4318 0.508)
			(layers "F.Cu" "F.Mask" "F.Paste")
			(net "LED_D22_R1")
		)
	)
	(footprint ""
		(layer "F.Cu")
		(at 35.031172 -83.816952 -90)
		(property "Reference" "R657"
			(at 0 0 270)
			(layer "F.SilkS")
			(hide yes)
			(effects
				(font
					(size 1.27 1.27)
				)
			)
		)
		(property "Value" ""
			(at 0 0 270)
			(layer "F.Fab")
			(effects
				(font
					(size 1.27 1.27)
				)
			)
		)
		(duplicate_pad_numbers_are_jumpers no)
		(fp_line
			(start -0.7874 0.4064)
			(end -0.7874 -0.4064)
			(stroke
				(width 0.1524)
				(type default)
			)
			(layer "F.SilkS")
		)
		(fp_line
			(start 0.7874 0.4064)
			(end -0.7874 0.4064)
			(stroke
				(width 0.1524)
				(type default)
			)
			(layer "F.SilkS")
		)
		(fp_line
			(start -0.7874 -0.4064)
			(end 0.7874 -0.4064)
			(stroke
				(width 0.1524)
				(type default)
			)
			(layer "F.SilkS")
		)
		(fp_line
			(start 0.7874 -0.4064)
			(end 0.7874 0.4064)
			(stroke
				(width 0.1524)
				(type default)
			)
			(layer "F.SilkS")
		)
		(fp_line
			(start -0.67945 0.3048)
			(end -0.67945 -0.305054)
			(stroke
				(width 0.1)
				(type default)
			)
			(layer "F.Fab")
		)
		(fp_line
			(start -0.12065 0.3048)
			(end -0.67945 0.3048)
			(stroke
				(width 0.1)
				(type default)
			)
			(layer "F.Fab")
		)
		(fp_line
			(start 0.120396 0.3048)
			(end 0.120396 0.2794)
			(stroke
				(width 0.1)
				(type default)
			)
			(layer "F.Fab")
		)
		(fp_line
			(start 0.67945 0.3048)
			(end 0.120396 0.3048)
			(stroke
				(width 0.1)
				(type default)
			)
			(layer "F.Fab")
		)
		(fp_line
			(start -0.12065 0.2794)
			(end -0.12065 0.3048)
			(stroke
				(width 0.1)
				(type default)
			)
			(layer "F.Fab")
		)
		(fp_line
			(start 0.120396 0.2794)
			(end -0.12065 0.2794)
			(stroke
				(width 0.1)
				(type default)
			)
			(layer "F.Fab")
		)
		(fp_line
			(start -0.12065 -0.2794)
			(end 0.12065 -0.2794)
			(stroke
				(width 0.1)
				(type default)
			)
			(layer "F.Fab")
		)
		(fp_line
			(start 0.12065 -0.2794)
			(end 0.12065 -0.3048)
			(stroke
				(width 0.1)
				(type default)
			)
			(layer "F.Fab")
		)
		(fp_line
			(start 0.12065 -0.3048)
			(end 0.67945 -0.3048)
			(stroke
				(width 0.1)
				(type default)
			)
			(layer "F.Fab")
		)
		(fp_line
			(start 0.67945 -0.3048)
			(end 0.67945 0.3048)
			(stroke
				(width 0.1)
				(type default)
			)
			(layer "F.Fab")
		)
		(fp_line
			(start -0.67945 -0.305054)
			(end -0.12065 -0.305054)
			(stroke
				(width 0.1)
				(type default)
			)
			(layer "F.Fab")
		)
		(fp_line
			(start -0.12065 -0.305054)
			(end -0.12065 -0.2794)
			(stroke
				(width 0.1)
				(type default)
			)
			(layer "F.Fab")
		)
		(pad "1" smd circle
			(at -0.40005 0 270)
			(size 0 0)
			(layers "F.Cu" "F.Mask" "F.Paste")
			(net "P3V3_AUX")
		)
		(pad "2" smd circle
			(at 0.40005 0 270)
			(size 0 0)
			(layers "F.Cu" "F.Mask" "F.Paste")
			(net "EMMC_DT2_R")
		)
	)
)
